(kicad_pcb
	(version 20260206)
	(generator "pcbnew")
	(generator_version "10.0")
	(general
		(thickness 1.6)
		(legacy_teardrops no)
	)
	(paper "A4")
	(title_block
		(title "04192023_DAF0TMB3IC0_F0TG_MB_C_brd_V02_OCP.brd")
		(comment 1 "Grand Teton / footprints 5338-5340 of 8354")
	)
	(layers
		(0 "F.Cu" signal "TOP")
		(4 "In1.Cu" signal "GND")
		(6 "In2.Cu" signal "IN1")
		(8 "In3.Cu" signal "GND1")
		(10 "In4.Cu" signal "IN2")
		(12 "In5.Cu" signal "GND2")
		(14 "In6.Cu" signal "IN3")
		(16 "In7.Cu" signal "GND3")
		(18 "In8.Cu" signal "VCC")
		(20 "In9.Cu" signal "VCC1")
		(22 "In10.Cu" signal "GND4")
		(24 "In11.Cu" signal "IN4")
		(26 "In12.Cu" signal "GND5")
		(28 "In13.Cu" signal "IN5")
		(30 "In14.Cu" signal "GND6")
		(32 "In15.Cu" signal "IN6")
		(34 "In16.Cu" signal "GND7")
		(2 "B.Cu" signal "BOTTOM")
		(9 "F.Adhes" user "F.Adhesive")
		(11 "B.Adhes" user "B.Adhesive")
		(13 "F.Paste" user "Package Geometry/Pastemask Top")
		(15 "B.Paste" user "Package Geometry/Pastemask Bottom")
		(5 "F.SilkS" user "Ref Des/Silkscreen Top")
		(7 "B.SilkS" user "Ref Des/Silkscreen Bottom")
		(1 "F.Mask" user "Board Geometry/Soldermask Top")
		(3 "B.Mask" user "Board Geometry/Soldermask Bottom")
		(17 "Dwgs.User" user "User.Drawings")
		(19 "Cmts.User" user "User.Comments")
		(21 "Eco1.User" user "User.Eco1")
		(23 "Eco2.User" user "User.Eco2")
		(25 "Edge.Cuts" user "Board Geometry/Outline")
		(27 "Margin" user)
		(31 "F.CrtYd" user "Package Geometry/Place Bound Top")
		(29 "B.CrtYd" user "Package Geometry/Place Bound Bottom")
		(35 "F.Fab" user "Ref Des/Assembly Top")
		(33 "B.Fab" user "Ref Des/Assembly Bottom")
	)
	(footprint ""
		(layer "B.Cu")
		(at 378.398278 -142.361158 -90)
		(property "Reference" "PU42"
			(at 5.846572 1.250696 0)
			(unlocked yes)
			(layer "B.SilkS")
			(effects
				(font
					(size 0.7874 0.5842)
					(thickness 0.1524)
				)
				(justify mirror)
			)
		)
		(property "Value" ""
			(at 0 0 90)
			(layer "B.Fab")
			(effects
				(font
					(size 1.27 1.27)
				)
				(justify mirror)
			)
		)
		(duplicate_pad_numbers_are_jumpers no)
		(fp_line
			(start -3.024886 3.024886)
			(end -2.428494 3.024886)
			(stroke
				(width 0.1524)
				(type default)
			)
			(layer "B.SilkS")
		)
		(fp_line
			(start 2.428494 3.024886)
			(end 3.024886 3.024886)
			(stroke
				(width 0.1524)
				(type default)
			)
			(layer "B.SilkS")
		)
		(fp_line
			(start 3.024886 3.024886)
			(end 3.024886 2.428494)
			(stroke
				(width 0.1524)
				(type default)
			)
			(layer "B.SilkS")
		)
		(fp_line
			(start -3.024886 2.428494)
			(end -3.024886 3.024886)
			(stroke
				(width 0.1524)
				(type default)
			)
			(layer "B.SilkS")
		)
		(fp_line
			(start 3.024886 -2.428494)
			(end 3.024886 -3.024886)
			(stroke
				(width 0.1524)
				(type default)
			)
			(layer "B.SilkS")
		)
		(fp_line
			(start -3.024886 -3.024886)
			(end -3.024886 -2.428494)
			(stroke
				(width 0.1524)
				(type default)
			)
			(layer "B.SilkS")
		)
		(fp_line
			(start -2.428494 -3.024886)
			(end -3.024886 -3.024886)
			(stroke
				(width 0.1524)
				(type default)
			)
			(layer "B.SilkS")
		)
		(fp_line
			(start 3.024886 -3.024886)
			(end 2.428494 -3.024886)
			(stroke
				(width 0.1524)
				(type default)
			)
			(layer "B.SilkS")
		)
		(fp_poly
			(pts
				(xy 4.10337 -1.79197) (xy 3.307588 -2.192274) (xy 4.10337 -2.587752)
			)
			(stroke
				(width 0)
				(type default)
			)
			(fill yes)
			(layer "B.SilkS")
		)
		(fp_line
			(start -3.024886 3.024886)
			(end 3.024886 3.024886)
			(stroke
				(width 0.1)
				(type default)
			)
			(layer "B.Fab")
		)
		(fp_line
			(start 3.024886 3.024886)
			(end 3.024886 -3.024886)
			(stroke
				(width 0.1)
				(type default)
			)
			(layer "B.Fab")
		)
		(fp_line
			(start -3.024886 -3.024886)
			(end -3.024886 3.024886)
			(stroke
				(width 0.1)
				(type default)
			)
			(layer "B.Fab")
		)
		(fp_line
			(start 3.024886 -3.024886)
			(end -3.024886 -3.024886)
			(stroke
				(width 0.1)
				(type default)
			)
			(layer "B.Fab")
		)
		(fp_poly
			(pts
				(xy 3.332226 -2.199894) (xy 4.348226 -1.691894) (xy 4.348226 -2.707894)
			)
			(stroke
				(width 0)
				(type default)
			)
			(fill yes)
			(layer "B.Fab")
		)
		(pad "1" smd rect
			(at 2.875026 -2.199894 180)
			(size 0.1778 0.6604)
			(layers "B.Cu" "B.Mask" "B.Paste")
			(net "PVDDCR_SOC_P0_PWM1")
		)
		(pad "2" smd rect
			(at 2.875026 -1.800098 180)
			(size 0.1778 0.6604)
			(layers "B.Cu" "B.Mask" "B.Paste")
			(net "PVDDCR_SOC_P0_PWM2")
		)
		(pad "3" smd rect
			(at 2.875026 -1.400048 180)
			(size 0.1778 0.6604)
			(layers "B.Cu" "B.Mask" "B.Paste")
			(net "PVDDCR_SOC_P0_PWM3")
		)
		(pad "4" smd rect
			(at 2.875026 -0.999998 180)
			(size 0.1778 0.6604)
			(layers "B.Cu" "B.Mask" "B.Paste")
			(net "NC_PVDDCR_CPU0_P0_PWM9")
		)
		(pad "5" smd rect
			(at 2.875026 -0.599948 180)
			(size 0.1778 0.6604)
			(layers "B.Cu" "B.Mask" "B.Paste")
			(net "NC_PVDDCR_CPU0_P0_PWM8")
		)
		(pad "6" smd rect
			(at 2.875026 -0.199898 180)
			(size 0.1778 0.6604)
			(layers "B.Cu" "B.Mask" "B.Paste")
			(net "NC_PVDDCR_CPU0_P0_PWM7")
		)
		(pad "7" smd rect
			(at 2.875026 0.199898 180)
			(size 0.1778 0.6604)
			(layers "B.Cu" "B.Mask" "B.Paste")
			(net "PVDDCR_CPU0_P0_PWM6")
		)
		(pad "8" smd rect
			(at 2.875026 0.599948 180)
			(size 0.1778 0.6604)
			(layers "B.Cu" "B.Mask" "B.Paste")
			(net "PVDDCR_CPU0_P0_PWM5")
		)
		(pad "9" smd rect
			(at 2.875026 0.999998 180)
			(size 0.1778 0.6604)
			(layers "B.Cu" "B.Mask" "B.Paste")
			(net "PVDDCR_CPU0_P0_PWM4")
		)
		(pad "10" smd rect
			(at 2.875026 1.400048 180)
			(size 0.1778 0.6604)
			(layers "B.Cu" "B.Mask" "B.Paste")
			(net "PVDDCR_CPU0_P0_PWM3")
		)
		(pad "11" smd rect
			(at 2.875026 1.800098 180)
			(size 0.1778 0.6604)
			(layers "B.Cu" "B.Mask" "B.Paste")
			(net "PVDDCR_CPU0_P0_PWM2")
		)
		(pad "12" smd rect
			(at 2.875026 2.199894 180)
			(size 0.1778 0.6604)
			(layers "B.Cu" "B.Mask" "B.Paste")
			(net "PVDDCR_CPU0_P0_PWM1")
		)
		(pad "13" smd rect
			(at 2.199894 2.875026 90)
			(size 0.1778 0.6604)
			(layers "B.Cu" "B.Mask" "B.Paste")
			(net "PVDDCR_CPU0_P0_PMSDA_R")
		)
		(pad "14" smd rect
			(at 1.800098 2.875026 90)
			(size 0.1778 0.6604)
			(layers "B.Cu" "B.Mask" "B.Paste")
			(net "PVDDCR_CPU0_P0_PMSCL_R")
		)
		(pad "15" smd rect
			(at 1.400048 2.875026 90)
			(size 0.1778 0.6604)
			(layers "B.Cu" "B.Mask" "B.Paste")
			(net "PVDDCR_CPU0_P0_PMALERT_R")
		)
		(pad "16" smd rect
			(at 0.999998 2.875026 90)
			(size 0.1778 0.6604)
			(layers "B.Cu" "B.Mask" "B.Paste")
			(net "PWRGD_PVDDCR_CPU0_P0_R")
		)
		(pad "17" smd rect
			(at 0.599948 2.875026 90)
			(size 0.1778 0.6604)
			(layers "B.Cu" "B.Mask" "B.Paste")
			(net "PVDDCR_CPU0_P0_EN_R")
		)
		(pad "18" smd rect
			(at 0.199898 2.875026 90)
			(size 0.1778 0.6604)
			(layers "B.Cu" "B.Mask" "B.Paste")
			(net "PVDDCR_CPU0_P0_RESET_N_R")
		)
		(pad "19" smd rect
			(at -0.199898 2.875026 90)
			(size 0.1778 0.6604)
			(layers "B.Cu" "B.Mask" "B.Paste")
			(net "PVDD18_S5_P0")
		)
		(pad "20" smd rect
			(at -0.599948 2.875026 90)
			(size 0.1778 0.6604)
			(layers "B.Cu" "B.Mask" "B.Paste")
			(net "PWRGD_PVDDCR_SOC_P0_R")
		)
		(pad "21" smd rect
			(at -0.999998 2.875026 90)
			(size 0.1778 0.6604)
			(layers "B.Cu" "B.Mask" "B.Paste")
			(net "SVID_PVDDCR_CPU0_P0_SVD_R1")
		)
		(pad "22" smd rect
			(at -1.400048 2.875026 90)
			(size 0.1778 0.6604)
			(layers "B.Cu" "B.Mask" "B.Paste")
			(net "SVID_PVDDCR_CPU0_P0_SVC_R1")
		)
		(pad "23" smd rect
			(at -1.800098 2.875026 90)
			(size 0.1778 0.6604)
			(layers "B.Cu" "B.Mask" "B.Paste")
			(net "SVID_PVDDCR_CPU0_P0_SVTO_R")
		)
		(pad "24" smd rect
			(at -2.199894 2.875026 90)
			(size 0.1778 0.6604)
			(layers "B.Cu" "B.Mask" "B.Paste")
			(net "SVID_PVDDCR_CPU0_P0_SVTI_R")
		)
		(pad "25" smd rect
			(at -2.875026 2.199894 180)
			(size 0.1778 0.6604)
			(layers "B.Cu" "B.Mask" "B.Paste")
			(net "VSENSE_PVDDCR_CPU0_P0_VSEN0")
		)
		(pad "26" smd rect
			(at -2.875026 1.800098 180)
			(size 0.1778 0.6604)
			(layers "B.Cu" "B.Mask" "B.Paste")
			(net "VSENSE_VSS_SENSE_A_P0")
		)
		(pad "27" smd rect
			(at -2.875026 1.400048 180)
			(size 0.1778 0.6604)
			(layers "B.Cu" "B.Mask" "B.Paste")
			(net "PVDDCR_CPU0_P0_IMON1")
		)
		(pad "28" smd rect
			(at -2.875026 0.999998 180)
			(size 0.1778 0.6604)
			(layers "B.Cu" "B.Mask" "B.Paste")
			(net "PVDDCR_CPU0_P0_IMON2")
		)
		(pad "29" smd rect
			(at -2.875026 0.599948 180)
			(size 0.1778 0.6604)
			(layers "B.Cu" "B.Mask" "B.Paste")
			(net "PVDDCR_CPU0_P0_IMON3")
		)
		(pad "30" smd rect
			(at -2.875026 0.199898 180)
			(size 0.1778 0.6604)
			(layers "B.Cu" "B.Mask" "B.Paste")
			(net "PVDDCR_CPU0_P0_IMON4")
		)
		(pad "31" smd rect
			(at -2.875026 -0.199898 180)
			(size 0.1778 0.6604)
			(layers "B.Cu" "B.Mask" "B.Paste")
			(net "PVDDCR_CPU0_P0_IMON5")
		)
		(pad "32" smd rect
			(at -2.875026 -0.599948 180)
			(size 0.1778 0.6604)
			(layers "B.Cu" "B.Mask" "B.Paste")
			(net "PVDDCR_CPU0_P0_IMON6")
		)
		(pad "33" smd rect
			(at -2.875026 -0.999998 180)
			(size 0.1778 0.6604)
			(layers "B.Cu" "B.Mask" "B.Paste")
			(net "NC_PVDDCR_CPU0_P0_IMON7")
		)
		(pad "34" smd rect
			(at -2.875026 -1.400048 180)
			(size 0.1778 0.6604)
			(layers "B.Cu" "B.Mask" "B.Paste")
			(net "NC_PVDDCR_CPU0_P0_IMON8")
		)
		(pad "35" smd rect
			(at -2.875026 -1.800098 180)
			(size 0.1778 0.6604)
			(layers "B.Cu" "B.Mask" "B.Paste")
			(net "NC_PVDDCR_CPU0_P0_IMON9")
		)
		(pad "36" smd rect
			(at -2.875026 -2.199894 180)
			(size 0.1778 0.6604)
			(layers "B.Cu" "B.Mask" "B.Paste")
			(net "PVDDCR_SOC_P0_IMON3")
		)
		(pad "37" smd rect
			(at -2.199894 -2.875026 90)
			(size 0.1778 0.6604)
			(layers "B.Cu" "B.Mask" "B.Paste")
			(net "PVDDCR_SOC_P0_IMON2")
		)
		(pad "38" smd rect
			(at -1.800098 -2.875026 90)
			(size 0.1778 0.6604)
			(layers "B.Cu" "B.Mask" "B.Paste")
			(net "PVDDCR_SOC_P0_IMON1")
		)
		(pad "39" smd rect
			(at -1.400048 -2.875026 90)
			(size 0.1778 0.6604)
			(layers "B.Cu" "B.Mask" "B.Paste")
			(net "VSENSE_VSS_SENSE_A_P0")
		)
		(pad "40" smd rect
			(at -0.999998 -2.875026 90)
			(size 0.1778 0.6604)
			(layers "B.Cu" "B.Mask" "B.Paste")
			(net "VSENSE_PVDDCR_SOC_P0_VSEN1")
		)
		(pad "41" smd rect
			(at -0.599948 -2.875026 90)
			(size 0.1778 0.6604)
			(layers "B.Cu" "B.Mask" "B.Paste")
			(net "PVDDCR_CPU0_P0_OCP_N_R")
		)
		(pad "42" smd rect
			(at -0.199898 -2.875026 90)
			(size 0.1778 0.6604)
			(layers "B.Cu" "B.Mask" "B.Paste")
			(net "PVDDCR_SOC_P0_EN//ADDR_CFG")
		)
		(pad "43" smd rect
			(at 0.199898 -2.875026 90)
			(size 0.1778 0.6604)
			(layers "B.Cu" "B.Mask" "B.Paste")
			(net "PVDDCR_SOC_P0_TEMP1")
		)
		(pad "44" smd rect
			(at 0.599948 -2.875026 90)
			(size 0.1778 0.6604)
			(layers "B.Cu" "B.Mask" "B.Paste")
			(net "PVDDCR_CPU0_P0_TEMP0")
		)
		(pad "45" smd rect
			(at 0.999998 -2.875026 90)
			(size 0.1778 0.6604)
			(layers "B.Cu" "B.Mask" "B.Paste")
			(net "PVDDCR_CPU0_P0_VMON")
		)
		(pad "46" smd rect
			(at 1.400048 -2.875026 90)
			(size 0.1778 0.6604)
			(layers "B.Cu" "B.Mask" "B.Paste")
			(net "PVDDCR_CPU0_P0_VINSEN")
		)
		(pad "47" smd rect
			(at 1.800098 -2.875026 90)
			(size 0.1778 0.6604)
			(layers "B.Cu" "B.Mask" "B.Paste")
			(net "PVDDCR_CPU0_P0_VCC")
		)
		(pad "48" smd rect
			(at 2.199894 -2.875026 90)
			(size 0.1778 0.6604)
			(layers "B.Cu" "B.Mask" "B.Paste")
			(net "PVDDCR_CPU0_P0_VCCS")
		)
		(pad "TH" smd rect
			(at 0 0 90)
			(size 4.4196 4.4196)
			(layers "B.Cu" "B.Mask" "B.Paste")
			(net "GND")
		)
		(zone
			(layer "B.Cu")
			(hatch none 0.5)
			(connect_pads
				(clearance 0)
			)
			(min_thickness 0.25)
			(keepout
				(tracks not_allowed)
				(vias allowed)
				(pads allowed)
				(copperpour not_allowed)
				(footprints allowed)
			)
			(placement
				(enabled no)
				(sheetname "")
			)
			(fill
				(thermal_gap 0.5)
				(thermal_bridge_width 0.5)
				(island_removal_mode 0)
			)
			(polygon
				(pts
					(xy 378.423678 -139.867132) (xy 380.892304 -139.867132) (xy 380.892304 -144.855184) (xy 375.904252 -144.855184)
					(xy 375.904252 -139.867132) (xy 378.398278 -139.867132) (xy 378.398278 -140.100558) (xy 376.137678 -140.100558)
					(xy 376.137678 -144.621758) (xy 380.658878 -144.621758) (xy 380.658878 -140.100558) (xy 378.423678 -140.100558)
				)
			)
		)
	)
	(footprint ""
		(layer "B.Cu")
		(at 102.528878 -139.93241 90)
		(property "Reference" "PR183"
			(at 0 0 90)
			(layer "B.SilkS")
			(hide yes)
			(effects
				(font
					(size 1.27 1.27)
				)
				(justify mirror)
			)
		)
		(property "Value" ""
			(at 0 0 90)
			(layer "B.Fab")
			(effects
				(font
					(size 1.27 1.27)
				)
				(justify mirror)
			)
		)
		(duplicate_pad_numbers_are_jumpers no)
		(fp_line
			(start 0.7874 -0.4064)
			(end -0.7874 -0.4064)
			(stroke
				(width 0.1524)
				(type default)
			)
			(layer "B.SilkS")
		)
		(fp_line
			(start -0.7874 -0.4064)
			(end -0.7874 0.4064)
			(stroke
				(width 0.1524)
				(type default)
			)
			(layer "B.SilkS")
		)
		(fp_line
			(start 0.7874 0.4064)
			(end 0.7874 -0.4064)
			(stroke
				(width 0.1524)
				(type default)
			)
			(layer "B.SilkS")
		)
		(fp_line
			(start -0.7874 0.4064)
			(end 0.7874 0.4064)
			(stroke
				(width 0.1524)
				(type default)
			)
			(layer "B.SilkS")
		)
		(fp_line
			(start 0.67945 -0.305054)
			(end 0.12065 -0.305054)
			(stroke
				(width 0.1)
				(type default)
			)
			(layer "B.Fab")
		)
		(fp_line
			(start 0.12065 -0.305054)
			(end 0.12065 -0.2794)
			(stroke
				(width 0.1)
				(type default)
			)
			(layer "B.Fab")
		)
		(fp_line
			(start -0.12065 -0.3048)
			(end -0.67945 -0.3048)
			(stroke
				(width 0.1)
				(type default)
			)
			(layer "B.Fab")
		)
		(fp_line
			(start -0.67945 -0.3048)
			(end -0.67945 0.3048)
			(stroke
				(width 0.1)
				(type default)
			)
			(layer "B.Fab")
		)
		(fp_line
			(start 0.12065 -0.2794)
			(end -0.12065 -0.2794)
			(stroke
				(width 0.1)
				(type default)
			)
			(layer "B.Fab")
		)
		(fp_line
			(start -0.12065 -0.2794)
			(end -0.12065 -0.3048)
			(stroke
				(width 0.1)
				(type default)
			)
			(layer "B.Fab")
		)
		(fp_line
			(start 0.12065 0.2794)
			(end 0.12065 0.3048)
			(stroke
				(width 0.1)
				(type default)
			)
			(layer "B.Fab")
		)
		(fp_line
			(start -0.120396 0.2794)
			(end 0.12065 0.2794)
			(stroke
				(width 0.1)
				(type default)
			)
			(layer "B.Fab")
		)
		(fp_line
			(start 0.67945 0.3048)
			(end 0.67945 -0.305054)
			(stroke
				(width 0.1)
				(type default)
			)
			(layer "B.Fab")
		)
		(fp_line
			(start 0.12065 0.3048)
			(end 0.67945 0.3048)
			(stroke
				(width 0.1)
				(type default)
			)
			(layer "B.Fab")
		)
		(fp_line
			(start -0.120396 0.3048)
			(end -0.120396 0.2794)
			(stroke
				(width 0.1)
				(type default)
			)
			(layer "B.Fab")
		)
		(fp_line
			(start -0.67945 0.3048)
			(end -0.120396 0.3048)
			(stroke
				(width 0.1)
				(type default)
			)
			(layer "B.Fab")
		)
		(pad "1" smd circle
			(at 0.40005 0 270)
			(size 0 0)
			(layers "B.Cu" "B.Mask" "B.Paste")
			(net "PVDDCR_CPU0_P1_VCC")
		)
		(pad "2" smd circle
			(at -0.40005 0 270)
			(size 0 0)
			(layers "B.Cu" "B.Mask" "B.Paste")
			(net "P3V3_AUX")
		)
	)
	(footprint ""
		(layer "B.Cu")
		(at 302.133 -355.854 180)
		(property "Reference" "R8043"
			(at 0 0 0)
			(layer "B.SilkS")
			(hide yes)
			(effects
				(font
					(size 1.27 1.27)
				)
				(justify mirror)
			)
		)
		(property "Value" ""
			(at 0 0 0)
			(layer "B.Fab")
			(effects
				(font
					(size 1.27 1.27)
				)
				(justify mirror)
			)
		)
		(duplicate_pad_numbers_are_jumpers no)
		(fp_line
			(start 0.7874 0.4064)
			(end 0.7874 -0.4064)
			(stroke
				(width 0.1524)
				(type default)
			)
			(layer "B.SilkS")
		)
		(fp_line
			(start 0.7874 -0.4064)
			(end -0.7874 -0.4064)
			(stroke
				(width 0.1524)
				(type default)
			)
			(layer "B.SilkS")
		)
		(fp_line
			(start -0.7874 0.4064)
			(end 0.7874 0.4064)
			(stroke
				(width 0.1524)
				(type default)
			)
			(layer "B.SilkS")
		)
		(fp_line
			(start -0.7874 -0.4064)
			(end -0.7874 0.4064)
			(stroke
				(width 0.1524)
				(type default)
			)
			(layer "B.SilkS")
		)
		(fp_line
			(start 0.67945 0.3048)
			(end 0.67945 -0.305054)
			(stroke
				(width 0.1)
				(type default)
			)
			(layer "B.Fab")
		)
		(fp_line
			(start 0.67945 -0.305054)
			(end 0.12065 -0.305054)
			(stroke
				(width 0.1)
				(type default)
			)
			(layer "B.Fab")
		)
		(fp_line
			(start 0.12065 0.3048)
			(end 0.67945 0.3048)
			(stroke
				(width 0.1)
				(type default)
			)
			(layer "B.Fab")
		)
		(fp_line
			(start 0.12065 0.2794)
			(end 0.12065 0.3048)
			(stroke
				(width 0.1)
				(type default)
			)
			(layer "B.Fab")
		)
		(fp_line
			(start 0.12065 -0.2794)
			(end -0.12065 -0.2794)
			(stroke
				(width 0.1)
				(type default)
			)
			(layer "B.Fab")
		)
		(fp_line
			(start 0.12065 -0.305054)
			(end 0.12065 -0.2794)
			(stroke
				(width 0.1)
				(type default)
			)
			(layer "B.Fab")
		)
		(fp_line
			(start -0.120396 0.3048)
			(end -0.120396 0.2794)
			(stroke
				(width 0.1)
				(type default)
			)
			(layer "B.Fab")
		)
		(fp_line
			(start -0.120396 0.2794)
			(end 0.12065 0.2794)
			(stroke
				(width 0.1)
				(type default)
			)
			(layer "B.Fab")
		)
		(fp_line
			(start -0.12065 -0.2794)
			(end -0.12065 -0.3048)
			(stroke
				(width 0.1)
				(type default)
			)
			(layer "B.Fab")
		)
		(fp_line
			(start -0.12065 -0.3048)
			(end -0.67945 -0.3048)
			(stroke
				(width 0.1)
				(type default)
			)
			(layer "B.Fab")
		)
		(fp_line
			(start -0.67945 0.3048)
			(end -0.120396 0.3048)
			(stroke
				(width 0.1)
				(type default)
			)
			(layer "B.Fab")
		)
		(fp_line
			(start -0.67945 -0.3048)
			(end -0.67945 0.3048)
			(stroke
				(width 0.1)
				(type default)
			)
			(layer "B.Fab")
		)
		(pad "1" smd circle
			(at 0.40005 0)
			(size 0 0)
			(layers "B.Cu" "B.Mask" "B.Paste")
			(net "PVDD18_S5_P0")
		)
		(pad "2" smd circle
			(at -0.40005 0)
			(size 0 0)
			(layers "B.Cu" "B.Mask" "B.Paste")
			(net "SVID_PVDDCR_CPU1_P0_SVTO")
		)
	)
)
